(kicad_pcb
	(version 20241229)
	(generator "pcbnew")
	(generator_version "9.0")
	(general
		(thickness 1.62)
		(legacy_teardrops no)
	)
	(paper "A3")
	(title_block
		(title "COM Express 7 Baseboard")
		(date "2025-02-04")
		(rev "1.1.2")
		(company "Antmicro Ltd")
		(comment 1 "www.antmicro.com")
		(comment 9 "footprints 725-729 of 802")
	)
	(layers
		(0 "F.Cu" signal)
		(4 "In1.Cu" signal)
		(6 "In2.Cu" signal)
		(8 "In3.Cu" signal)
		(10 "In4.Cu" signal)
		(12 "In5.Cu" signal)
		(14 "In6.Cu" signal)
		(2 "B.Cu" signal)
		(9 "F.Adhes" user "F.Adhesive")
		(11 "B.Adhes" user "B.Adhesive")
		(13 "F.Paste" user)
		(15 "B.Paste" user)
		(5 "F.SilkS" user "F.Silkscreen")
		(7 "B.SilkS" user "B.Silkscreen")
		(1 "F.Mask" user)
		(3 "B.Mask" user)
		(17 "Dwgs.User" user "User.Drawings")
		(19 "Cmts.User" user "User.Comments")
		(21 "Eco1.User" user "User.Eco1")
		(23 "Eco2.User" user "User.Eco2")
		(25 "Edge.Cuts" user)
		(27 "Margin" user)
		(31 "F.CrtYd" user "F.Courtyard")
		(29 "B.CrtYd" user "B.Courtyard")
		(35 "F.Fab" user)
		(33 "B.Fab" user)
	)
	(footprint "antmicro-footprints:C_0402_1005Metric"
		(layer "B.Cu")
		(at 125.22 149.26 -90)
		(descr "Capacitor SMD 0402")
		(tags "capacitor SMD 0402")
		(property "Reference" "C176"
			(at -1.3 1.47 90)
			(layer "B.SilkS")
			(effects
				(font
					(size 0.7 0.7)
					(thickness 0.15)
				)
				(justify left bottom mirror)
			)
		)
		(property "Value" "C_100n_0402"
			(at -1.022927 -2.155213 90)
			(layer "B.Fab")
			(effects
				(font
					(size 0.7 0.7)
					(thickness 0.15)
				)
				(justify left bottom mirror)
			)
		)
		(property "Datasheet" "https://www.murata.com/products/productdetail?partno=GRM155R61H104KE14%23"
			(at 0 0 270)
			(layer "F.Fab")
			(hide yes)
			(effects
				(font
					(size 1.27 1.27)
					(thickness 0.15)
				)
			)
		)
		(property "Author" "Antmicro"
			(at -24.04 274.48 0)
			(layer "B.Fab")
			(hide yes)
			(effects
				(font
					(size 1 1)
					(thickness 0.15)
				)
				(justify mirror)
			)
		)
		(property "Dielectric" "X5R"
			(at -24.04 274.48 0)
			(layer "B.Fab")
			(hide yes)
			(effects
				(font
					(size 1 1)
					(thickness 0.15)
				)
				(justify mirror)
			)
		)
		(property "License" "Apache-2.0"
			(at -24.04 274.48 0)
			(layer "B.Fab")
			(hide yes)
			(effects
				(font
					(size 1 1)
					(thickness 0.15)
				)
				(justify mirror)
			)
		)
		(property "MPN" "GRM155R61H104KE14D"
			(at -24.04 274.48 0)
			(layer "B.Fab")
			(hide yes)
			(effects
				(font
					(size 1 1)
					(thickness 0.15)
				)
				(justify mirror)
			)
		)
		(property "Manufacturer" "Murata"
			(at -24.04 274.48 0)
			(layer "B.Fab")
			(hide yes)
			(effects
				(font
					(size 1 1)
					(thickness 0.15)
				)
				(justify mirror)
			)
		)
		(property "Public" "False"
			(at -24.04 274.48 0)
			(layer "B.Fab")
			(hide yes)
			(effects
				(font
					(size 1 1)
					(thickness 0.15)
				)
				(justify mirror)
			)
		)
		(property "Val" "100n"
			(at -24.04 274.48 0)
			(layer "B.Fab")
			(hide yes)
			(effects
				(font
					(size 1 1)
					(thickness 0.15)
				)
				(justify mirror)
			)
		)
		(property "Voltage" "50V"
			(at -24.04 274.48 0)
			(layer "B.Fab")
			(hide yes)
			(effects
				(font
					(size 1 1)
					(thickness 0.15)
				)
				(justify mirror)
			)
		)
		(sheetname "KR to SFI #2")
		(sheetfile "kr_sfi.kicad_sch")
		(attr smd)
		(fp_rect
			(start -0.925 0.47)
			(end 0.925 -0.47)
			(stroke
				(width 0.05)
				(type default)
			)
			(fill no)
			(layer "B.CrtYd")
		)
		(fp_line
			(start -0.494 0.25)
			(end -0.494 -0.248)
			(stroke
				(width 0.15)
				(type solid)
			)
			(layer "B.Fab")
		)
		(fp_line
			(start 0.504 0.25)
			(end -0.494 0.25)
			(stroke
				(width 0.15)
				(type solid)
			)
			(layer "B.Fab")
		)
		(fp_line
			(start -0.494 -0.248)
			(end 0.504 -0.248)
			(stroke
				(width 0.15)
				(type solid)
			)
			(layer "B.Fab")
		)
		(fp_line
			(start 0.504 -0.248)
			(end 0.504 0.25)
			(stroke
				(width 0.15)
				(type solid)
			)
			(layer "B.Fab")
		)
		(pad "1" smd roundrect
			(at -0.48 0 270)
			(size 0.59 0.64)
			(layers "B.Cu" "B.Mask" "B.Paste")
			(roundrect_rratio 0.25)
			(net 1 "GND")
			(pintype "passive")
			(teardrops
				(best_length_ratio 0.2)
				(max_length 1)
				(best_width_ratio 0.9)
				(max_width 2)
				(curved_edges yes)
				(filter_ratio 0.9)
				(enabled yes)
				(allow_two_segments yes)
				(prefer_zone_connections yes)
			)
		)
		(pad "2" smd roundrect
			(at 0.48 0 270)
			(size 0.59 0.64)
			(layers "B.Cu" "B.Mask" "B.Paste")
			(roundrect_rratio 0.25)
			(net 2 "+3V3")
			(pintype "passive")
			(teardrops
				(best_length_ratio 0.2)
				(max_length 1)
				(best_width_ratio 0.9)
				(max_width 2)
				(curved_edges yes)
				(filter_ratio 0.9)
				(enabled yes)
				(allow_two_segments yes)
				(prefer_zone_connections yes)
			)
		)
	)
	(footprint "antmicro-footprints:C_0603_1608Metric"
		(layer "B.Cu")
		(at 148.7 88.58 180)
		(descr "Capacitor SMD 0603")
		(tags "capacitor 0603")
		(property "Reference" "C82"
			(at -3.3 -0.48 0)
			(layer "B.SilkS")
			(effects
				(font
					(size 0.7 0.7)
					(thickness 0.15)
				)
				(justify left bottom mirror)
			)
		)
		(property "Value" "C_22u_16V_0603"
			(at -1.42757 -1.770288 0)
			(layer "B.Fab")
			(effects
				(font
					(size 0.7 0.7)
					(thickness 0.15)
				)
				(justify left bottom mirror)
			)
		)
		(property "Datasheet" "https://product.samsungsem.com/mlcc/CL10A226MO7JZN.do"
			(at 0 0 180)
			(layer "F.Fab")
			(hide yes)
			(effects
				(font
					(size 1.27 1.27)
					(thickness 0.15)
				)
			)
		)
		(property "Author" "Antmicro"
			(at 297.4 177.16 0)
			(layer "B.Fab")
			(hide yes)
			(effects
				(font
					(size 1 1)
					(thickness 0.15)
				)
				(justify mirror)
			)
		)
		(property "Dielectric" ""
			(at 297.4 177.16 0)
			(layer "B.Fab")
			(hide yes)
			(effects
				(font
					(size 1 1)
					(thickness 0.15)
				)
				(justify mirror)
			)
		)
		(property "License" "Apache-2.0"
			(at 297.4 177.16 0)
			(layer "B.Fab")
			(hide yes)
			(effects
				(font
					(size 1 1)
					(thickness 0.15)
				)
				(justify mirror)
			)
		)
		(property "MPN" "CL10A226MO7JZNC"
			(at 297.4 177.16 0)
			(layer "B.Fab")
			(hide yes)
			(effects
				(font
					(size 1 1)
					(thickness 0.15)
				)
				(justify mirror)
			)
		)
		(property "Manufacturer" "Samsung Electro-Mechanics"
			(at 297.4 177.16 0)
			(layer "B.Fab")
			(hide yes)
			(effects
				(font
					(size 1 1)
					(thickness 0.15)
				)
				(justify mirror)
			)
		)
		(property "Public" "False"
			(at 297.4 177.16 0)
			(layer "B.Fab")
			(hide yes)
			(effects
				(font
					(size 1 1)
					(thickness 0.15)
				)
				(justify mirror)
			)
		)
		(property "Val" "22u"
			(at 297.4 177.16 0)
			(layer "B.Fab")
			(hide yes)
			(effects
				(font
					(size 1 1)
					(thickness 0.15)
				)
				(justify mirror)
			)
		)
		(property "Voltage" "16V"
			(at 297.4 177.16 0)
			(layer "B.Fab")
			(hide yes)
			(effects
				(font
					(size 1 1)
					(thickness 0.15)
				)
				(justify mirror)
			)
		)
		(sheetname "M.2 key E")
		(sheetfile "m2keye.kicad_sch")
		(attr smd)
		(fp_line
			(start 0.15 0.4)
			(end -0.15 0.4)
			(stroke
				(width 0.15)
				(type solid)
			)
			(layer "B.SilkS")
		)
		(fp_line
			(start 0.15 -0.4)
			(end -0.15 -0.4)
			(stroke
				(width 0.15)
				(type solid)
			)
			(layer "B.SilkS")
		)
		(fp_rect
			(start -1.25 0.65)
			(end 1.25 -0.65)
			(stroke
				(width 0.05)
				(type solid)
			)
			(fill no)
			(layer "B.CrtYd")
		)
		(fp_rect
			(start -0.8 0.4)
			(end 0.8 -0.4)
			(stroke
				(width 0.15)
				(type solid)
			)
			(fill no)
			(layer "B.Fab")
		)
		(pad "1" smd roundrect
			(at -0.7 0 180)
			(size 0.8 1)
			(layers "B.Cu" "B.Mask" "B.Paste")
			(roundrect_rratio 0.2)
			(net 1 "GND")
			(pintype "passive")
			(teardrops
				(best_length_ratio 0.2)
				(max_length 1)
				(best_width_ratio 0.9)
				(max_width 2)
				(curved_edges yes)
				(filter_ratio 0.9)
				(enabled yes)
				(allow_two_segments yes)
				(prefer_zone_connections yes)
			)
		)
		(pad "2" smd roundrect
			(at 0.7 0 180)
			(size 0.8 1)
			(layers "B.Cu" "B.Mask" "B.Paste")
			(roundrect_rratio 0.2)
			(net 2 "+3V3")
			(pintype "passive")
			(teardrops
				(best_length_ratio 0.2)
				(max_length 1)
				(best_width_ratio 0.9)
				(max_width 2)
				(curved_edges yes)
				(filter_ratio 0.9)
				(enabled yes)
				(allow_two_segments yes)
				(prefer_zone_connections yes)
			)
		)
	)
	(footprint "antmicro-footprints:C_0402_1005Metric"
		(layer "B.Cu")
		(at 150.25 160.23 -90)
		(descr "Capacitor SMD 0402")
		(tags "capacitor SMD 0402")
		(property "Reference" "C26"
			(at -2.97 -0.45 90)
			(layer "B.SilkS")
			(effects
				(font
					(size 0.7 0.7)
					(thickness 0.15)
				)
				(justify left bottom mirror)
			)
		)
		(property "Value" "C_100n_0402"
			(at -1.022927 -2.155213 90)
			(layer "B.Fab")
			(effects
				(font
					(size 0.7 0.7)
					(thickness 0.15)
				)
				(justify left bottom mirror)
			)
		)
		(property "Datasheet" "https://www.murata.com/products/productdetail?partno=GRM155R61H104KE14%23"
			(at 0 0 270)
			(layer "F.Fab")
			(hide yes)
			(effects
				(font
					(size 1.27 1.27)
					(thickness 0.15)
				)
			)
		)
		(property "Author" "Antmicro"
			(at -9.98 310.48 0)
			(layer "B.Fab")
			(hide yes)
			(effects
				(font
					(size 1 1)
					(thickness 0.15)
				)
				(justify mirror)
			)
		)
		(property "Dielectric" "X5R"
			(at -9.98 310.48 0)
			(layer "B.Fab")
			(hide yes)
			(effects
				(font
					(size 1 1)
					(thickness 0.15)
				)
				(justify mirror)
			)
		)
		(property "License" "Apache-2.0"
			(at -9.98 310.48 0)
			(layer "B.Fab")
			(hide yes)
			(effects
				(font
					(size 1 1)
					(thickness 0.15)
				)
				(justify mirror)
			)
		)
		(property "MPN" "GRM155R61H104KE14D"
			(at -9.98 310.48 0)
			(layer "B.Fab")
			(hide yes)
			(effects
				(font
					(size 1 1)
					(thickness 0.15)
				)
				(justify mirror)
			)
		)
		(property "Manufacturer" "Murata"
			(at -9.98 310.48 0)
			(layer "B.Fab")
			(hide yes)
			(effects
				(font
					(size 1 1)
					(thickness 0.15)
				)
				(justify mirror)
			)
		)
		(property "Public" "False"
			(at -9.98 310.48 0)
			(layer "B.Fab")
			(hide yes)
			(effects
				(font
					(size 1 1)
					(thickness 0.15)
				)
				(justify mirror)
			)
		)
		(property "Val" "100n"
			(at -9.98 310.48 0)
			(layer "B.Fab")
			(hide yes)
			(effects
				(font
					(size 1 1)
					(thickness 0.15)
				)
				(justify mirror)
			)
		)
		(property "Voltage" "50V"
			(at -9.98 310.48 0)
			(layer "B.Fab")
			(hide yes)
			(effects
				(font
					(size 1 1)
					(thickness 0.15)
				)
				(justify mirror)
			)
		)
		(sheetname "2xSFP+")
		(sheetfile "2xSFP+.kicad_sch")
		(attr smd)
		(fp_rect
			(start -0.925 0.47)
			(end 0.925 -0.47)
			(stroke
				(width 0.05)
				(type default)
			)
			(fill no)
			(layer "B.CrtYd")
		)
		(fp_line
			(start -0.494 0.25)
			(end -0.494 -0.248)
			(stroke
				(width 0.15)
				(type solid)
			)
			(layer "B.Fab")
		)
		(fp_line
			(start 0.504 0.25)
			(end -0.494 0.25)
			(stroke
				(width 0.15)
				(type solid)
			)
			(layer "B.Fab")
		)
		(fp_line
			(start -0.494 -0.248)
			(end 0.504 -0.248)
			(stroke
				(width 0.15)
				(type solid)
			)
			(layer "B.Fab")
		)
		(fp_line
			(start 0.504 -0.248)
			(end 0.504 0.25)
			(stroke
				(width 0.15)
				(type solid)
			)
			(layer "B.Fab")
		)
		(pad "1" smd roundrect
			(at -0.48 0 270)
			(size 0.59 0.64)
			(layers "B.Cu" "B.Mask" "B.Paste")
			(roundrect_rratio 0.25)
			(net 1 "GND")
			(pintype "passive")
			(teardrops
				(best_length_ratio 0.2)
				(max_length 1)
				(best_width_ratio 0.9)
				(max_width 2)
				(curved_edges yes)
				(filter_ratio 0.9)
				(enabled yes)
				(allow_two_segments yes)
				(prefer_zone_connections yes)
			)
		)
		(pad "2" smd roundrect
			(at 0.48 0 270)
			(size 0.59 0.64)
			(layers "B.Cu" "B.Mask" "B.Paste")
			(roundrect_rratio 0.25)
			(net 2 "+3V3")
			(pintype "passive")
			(teardrops
				(best_length_ratio 0.2)
				(max_length 1)
				(best_width_ratio 0.9)
				(max_width 2)
				(curved_edges yes)
				(filter_ratio 0.9)
				(enabled yes)
				(allow_two_segments yes)
				(prefer_zone_connections yes)
			)
		)
	)
	(footprint "antmicro-footprints:C_0402_1005Metric"
		(layer "B.Cu")
		(at 109.811 165.869 180)
		(descr "Capacitor SMD 0402")
		(tags "capacitor SMD 0402")
		(property "Reference" "C146"
			(at -3.689 -0.441 0)
			(layer "B.SilkS")
			(effects
				(font
					(size 0.7 0.7)
					(thickness 0.15)
				)
				(justify left bottom mirror)
			)
		)
		(property "Value" "C_220n_0402"
			(at -1.022927 -2.155213 0)
			(layer "B.Fab")
			(effects
				(font
					(size 0.7 0.7)
					(thickness 0.15)
				)
				(justify left bottom mirror)
			)
		)
		(property "Datasheet" "https://www.yageo.com/en/Chart/Download/pdf/CC0402KRX5R6BB224"
			(at 0 0 180)
			(layer "F.Fab")
			(hide yes)
			(effects
				(font
					(size 1.27 1.27)
					(thickness 0.15)
				)
			)
		)
		(property "Author" "Antmicro"
			(at 219.622 331.738 0)
			(layer "B.Fab")
			(hide yes)
			(effects
				(font
					(size 1 1)
					(thickness 0.15)
				)
				(justify mirror)
			)
		)
		(property "Dielectric" ""
			(at 219.622 331.738 0)
			(layer "B.Fab")
			(hide yes)
			(effects
				(font
					(size 1 1)
					(thickness 0.15)
				)
				(justify mirror)
			)
		)
		(property "License" "Apache-2.0"
			(at 219.622 331.738 0)
			(layer "B.Fab")
			(hide yes)
			(effects
				(font
					(size 1 1)
					(thickness 0.15)
				)
				(justify mirror)
			)
		)
		(property "MPN" "CC0402KRX5R6BB224"
			(at 219.622 331.738 0)
			(layer "B.Fab")
			(hide yes)
			(effects
				(font
					(size 1 1)
					(thickness 0.15)
				)
				(justify mirror)
			)
		)
		(property "Manufacturer" "YAGEO"
			(at 219.622 331.738 0)
			(layer "B.Fab")
			(hide yes)
			(effects
				(font
					(size 1 1)
					(thickness 0.15)
				)
				(justify mirror)
			)
		)
		(property "Public" "False"
			(at 219.622 331.738 0)
			(layer "B.Fab")
			(hide yes)
			(effects
				(font
					(size 1 1)
					(thickness 0.15)
				)
				(justify mirror)
			)
		)
		(property "Val" "220n"
			(at 219.622 331.738 0)
			(layer "B.Fab")
			(hide yes)
			(effects
				(font
					(size 1 1)
					(thickness 0.15)
				)
				(justify mirror)
			)
		)
		(property "Voltage" ""
			(at 219.622 331.738 0)
			(layer "B.Fab")
			(hide yes)
			(effects
				(font
					(size 1 1)
					(thickness 0.15)
				)
				(justify mirror)
			)
		)
		(sheetname "PCIe redriver")
		(sheetfile "pcie_redriver.kicad_sch")
		(attr smd)
		(fp_rect
			(start -0.925 0.47)
			(end 0.925 -0.47)
			(stroke
				(width 0.05)
				(type default)
			)
			(fill no)
			(layer "B.CrtYd")
		)
		(fp_line
			(start 0.504 0.25)
			(end -0.494 0.25)
			(stroke
				(width 0.15)
				(type solid)
			)
			(layer "B.Fab")
		)
		(fp_line
			(start 0.504 -0.248)
			(end 0.504 0.25)
			(stroke
				(width 0.15)
				(type solid)
			)
			(layer "B.Fab")
		)
		(fp_line
			(start -0.494 0.25)
			(end -0.494 -0.248)
			(stroke
				(width 0.15)
				(type solid)
			)
			(layer "B.Fab")
		)
		(fp_line
			(start -0.494 -0.248)
			(end 0.504 -0.248)
			(stroke
				(width 0.15)
				(type solid)
			)
			(layer "B.Fab")
		)
		(pad "1" smd roundrect
			(at -0.48 0 180)
			(size 0.59 0.64)
			(layers "B.Cu" "B.Mask" "B.Paste")
			(roundrect_rratio 0.25)
			(net 966 "/PCIe redriver/PCIe_{O}_C.TX0-")
			(pintype "passive")
			(teardrops
				(best_length_ratio 0.2)
				(max_length 1)
				(best_width_ratio 0.9)
				(max_width 2)
				(curved_edges yes)
				(filter_ratio 0.9)
				(enabled yes)
				(allow_two_segments yes)
				(prefer_zone_connections yes)
			)
		)
		(pad "2" smd roundrect
			(at 0.48 0 180)
			(size 0.59 0.64)
			(layers "B.Cu" "B.Mask" "B.Paste")
			(roundrect_rratio 0.25)
			(net 95 "/OCuLink/PCIe_{x4}.TX0-")
			(pintype "passive")
			(teardrops
				(best_length_ratio 0.2)
				(max_length 1)
				(best_width_ratio 0.9)
				(max_width 2)
				(curved_edges yes)
				(filter_ratio 0.9)
				(enabled yes)
				(allow_two_segments yes)
				(prefer_zone_connections yes)
			)
		)
	)
	(footprint "antmicro-footprints:R_0402_1005Metric"
		(layer "B.Cu")
		(at 145.05 169.16 -90)
		(descr "Resistor SMD 0402")
		(tags "resistor SMD 0402")
		(property "Reference" "R53"
			(at -3.9 13.5 90)
			(layer "B.SilkS")
			(effects
				(font
					(size 0.7 0.7)
					(thickness 0.15)
				)
				(justify left bottom mirror)
			)
		)
		(property "Value" "R_1k_0402"
			(at -1.011843 -1.772047 90)
			(layer "B.Fab")
			(effects
				(font
					(size 0.7 0.7)
					(thickness 0.15)
				)
				(justify left bottom mirror)
			)
		)
		(property "Datasheet" "https://www.bourns.com/docs/product-datasheets/cr.pdf"
			(at 0 0 270)
			(layer "F.Fab")
			(hide yes)
			(effects
				(font
					(size 1.27 1.27)
					(thickness 0.15)
				)
			)
		)
		(property "Author" "Antmicro"
			(at -24.11 314.21 0)
			(layer "B.Fab")
			(hide yes)
			(effects
				(font
					(size 1 1)
					(thickness 0.15)
				)
				(justify mirror)
			)
		)
		(property "License" "Apache-2.0"
			(at -24.11 314.21 0)
			(layer "B.Fab")
			(hide yes)
			(effects
				(font
					(size 1 1)
					(thickness 0.15)
				)
				(justify mirror)
			)
		)
		(property "MPN" "CR0402-FX-1001GLF"
			(at -24.11 314.21 0)
			(layer "B.Fab")
			(hide yes)
			(effects
				(font
					(size 1 1)
					(thickness 0.15)
				)
				(justify mirror)
			)
		)
		(property "Manufacturer" "Bourns"
			(at -24.11 314.21 0)
			(layer "B.Fab")
			(hide yes)
			(effects
				(font
					(size 1 1)
					(thickness 0.15)
				)
				(justify mirror)
			)
		)
		(property "Public" "False"
			(at -24.11 314.21 0)
			(layer "B.Fab")
			(hide yes)
			(effects
				(font
					(size 1 1)
					(thickness 0.15)
				)
				(justify mirror)
			)
		)
		(property "Tolerance" "1%"
			(at -24.11 314.21 0)
			(layer "B.Fab")
			(hide yes)
			(effects
				(font
					(size 1 1)
					(thickness 0.15)
				)
				(justify mirror)
			)
		)
		(property "Val" "1k"
			(at -24.11 314.21 0)
			(layer "B.Fab")
			(hide yes)
			(effects
				(font
					(size 1 1)
					(thickness 0.15)
				)
				(justify mirror)
			)
		)
		(sheetname "2xSFP+")
		(sheetfile "2xSFP+.kicad_sch")
		(attr smd)
		(fp_rect
			(start -0.925 0.47)
			(end 0.925 -0.47)
			(stroke
				(width 0.05)
				(type default)
			)
			(fill no)
			(layer "B.CrtYd")
		)
		(fp_rect
			(start -0.5 0.25)
			(end 0.5 -0.25)
			(stroke
				(width 0.15)
				(type solid)
			)
			(fill no)
			(layer "B.Fab")
		)
		(pad "1" smd roundrect
			(at -0.48 0 270)
			(size 0.59 0.64)
			(layers "B.Cu" "B.Mask" "B.Paste")
			(roundrect_rratio 0.25)
			(net 168 "Net-(J2A-RX_{LOS})")
			(pintype "passive")
			(teardrops
				(best_length_ratio 0.2)
				(max_length 1)
				(best_width_ratio 0.9)
				(max_width 2)
				(curved_edges yes)
				(filter_ratio 0.9)
				(enabled yes)
				(allow_two_segments yes)
				(prefer_zone_connections yes)
			)
		)
		(pad "2" smd roundrect
			(at 0.48 0 270)
			(size 0.59 0.64)
			(layers "B.Cu" "B.Mask" "B.Paste")
			(roundrect_rratio 0.25)
			(net 2 "+3V3")
			(pintype "passive")
			(teardrops
				(best_length_ratio 0.2)
				(max_length 1)
				(best_width_ratio 0.9)
				(max_width 2)
				(curved_edges yes)
				(filter_ratio 0.9)
				(enabled yes)
				(allow_two_segments yes)
				(prefer_zone_connections yes)
			)
		)
	)
)
